(kicad_pcb
	(version 20260206)
	(generator "pcbnew")
	(generator_version "10.0")
	(general
		(thickness 1.21888)
		(legacy_teardrops no)
	)
	(paper "A4")
	(title_block
		(title "timecard-beta-v1 — TimeCard-DC-V1.PcbDoc")
		(comment 1 "Time Appliance Project (Time Card) / footprints 103-108 of 120")
	)
	(layers
		(0 "F.Cu" signal "TOP")
		(4 "In1.Cu" signal "SGND")
		(6 "In2.Cu" signal "IN1")
		(8 "In3.Cu" signal "IN2")
		(10 "In4.Cu" signal "SGND1")
		(2 "B.Cu" signal "BOTTOM")
		(9 "F.Adhes" user "F.Adhesive")
		(11 "B.Adhes" user "B.Adhesive")
		(13 "F.Paste" user "Top Paste")
		(15 "B.Paste" user "Bottom Paste")
		(5 "F.SilkS" user "Top Overlay")
		(7 "B.SilkS" user "Bottom Overlay")
		(1 "F.Mask" user "Top Solder")
		(3 "B.Mask" user "Bottom Solder")
		(17 "Dwgs.User" user "User.Drawings")
		(19 "Cmts.User" user "User.Comments")
		(21 "Eco1.User" user "User.Eco1")
		(23 "Eco2.User" user "User.Eco2")
		(25 "Edge.Cuts" user)
		(27 "Margin" user)
		(31 "F.CrtYd" user "Top Courtyard")
		(29 "B.CrtYd" user "Bottom Courtyard")
		(35 "F.Fab" user "Top Component Center")
		(33 "B.Fab" user "Bottom Component Center")
	)
	(footprint "Connectors:PCIE_4LANE_EDGE"
		(layer "F.Cu")
		(at 120.638465 154.3547)
		(property "Reference" "P2"
			(at -12.64987 -0.282755 0)
			(unlocked yes)
			(layer "F.SilkS")
			(hide yes)
			(effects
				(font
					(size 0.762 0.762)
					(thickness 0.2286)
				)
				(justify left bottom)
			)
		)
		(property "Value" "PCIex4"
			(at -5.44907 18.65122 0)
			(unlocked yes)
			(layer "F.SilkS")
			(hide yes)
			(effects
				(font
					(size 1.524 1.524)
					(thickness 0.254)
				)
				(justify left bottom)
			)
		)
		(sheetname "PCIe_JTAG")
		(sheetfile "PCIe_JTAG.kicad_sch")
		(duplicate_pad_numbers_are_jumpers no)
		(pad "A1" smd rect
			(at -16.49984 2.2286)
			(size 0.7112 3.2004)
			(layers "B.Cu" "B.Mask" "B.Paste")
			(net "PRSNT")
		)
		(pad "A2" smd rect
			(at -15.49985 2.7239)
			(size 0.7112 4.191)
			(layers "B.Cu" "B.Mask" "B.Paste")
			(net "+12V_PCIE")
		)
		(pad "A3" smd rect
			(at -14.49985 2.7239)
			(size 0.7112 4.191)
			(layers "B.Cu" "B.Mask" "B.Paste")
			(net "+12V_PCIE")
		)
		(pad "A4" smd rect
			(at -13.49985 2.7239)
			(size 0.7112 4.191)
			(layers "B.Cu" "B.Mask" "B.Paste")
			(net "GND")
		)
		(pad "A5" smd rect
			(at -12.49985 2.7239)
			(size 0.7112 4.191)
			(layers "B.Cu" "B.Mask" "B.Paste")
		)
		(pad "A6" smd rect
			(at -11.49985 2.7239)
			(size 0.7112 4.191)
			(layers "B.Cu" "B.Mask" "B.Paste")
		)
		(pad "A7" smd rect
			(at -10.49986 2.7239)
			(size 0.7112 4.191)
			(layers "B.Cu" "B.Mask" "B.Paste")
		)
		(pad "A8" smd rect
			(at -9.49986 2.7239)
			(size 0.7112 4.191)
			(layers "B.Cu" "B.Mask" "B.Paste")
		)
		(pad "A9" smd rect
			(at -8.49986 2.7239)
			(size 0.7112 4.191)
			(layers "B.Cu" "B.Mask" "B.Paste")
			(net "+3.3V_PCIE")
		)
		(pad "A10" smd rect
			(at -7.49986 2.7239)
			(size 0.7112 4.191)
			(layers "B.Cu" "B.Mask" "B.Paste")
			(net "+3.3V_PCIE")
		)
		(pad "A11" smd rect
			(at -6.49986 2.7239)
			(size 0.7112 4.191)
			(layers "B.Cu" "B.Mask" "B.Paste")
			(net "PCIE_PERST")
		)
		(pad "A12" smd rect
			(at -3.49987 2.7239)
			(size 0.7112 4.191)
			(layers "B.Cu" "B.Mask" "B.Paste")
			(net "GND")
		)
		(pad "A13" smd rect
			(at -2.49987 2.7239)
			(size 0.7112 4.191)
			(layers "B.Cu" "B.Mask" "B.Paste")
			(net "NetC44_1")
		)
		(pad "A14" smd rect
			(at -1.49987 2.7239)
			(size 0.7112 4.191)
			(layers "B.Cu" "B.Mask" "B.Paste")
			(net "NetC45_1")
		)
		(pad "A15" smd rect
			(at -0.49988 2.7239)
			(size 0.7112 4.191)
			(layers "B.Cu" "B.Mask" "B.Paste")
			(net "GND")
		)
		(pad "A16" smd rect
			(at 0.50012 2.7239)
			(size 0.7112 4.191)
			(layers "B.Cu" "B.Mask" "B.Paste")
			(net "NetC46_1")
		)
		(pad "A17" smd rect
			(at 1.50012 2.7239)
			(size 0.7112 4.191)
			(layers "B.Cu" "B.Mask" "B.Paste")
			(net "NetC47_1")
		)
		(pad "A18" smd rect
			(at 2.50012 2.7239)
			(size 0.7112 4.191)
			(layers "B.Cu" "B.Mask" "B.Paste")
			(net "GND")
		)
		(pad "A19" smd rect
			(at 3.50012 2.7239)
			(size 0.7112 4.191)
			(layers "B.Cu" "B.Mask" "B.Paste")
		)
		(pad "A20" smd rect
			(at 4.50011 2.7239)
			(size 0.7112 4.191)
			(layers "B.Cu" "B.Mask" "B.Paste")
			(net "GND")
		)
		(pad "A21" smd rect
			(at 5.50011 2.7239)
			(size 0.7112 4.191)
			(layers "B.Cu" "B.Mask" "B.Paste")
			(net "NetC48_1")
		)
		(pad "A22" smd rect
			(at 6.50011 2.7239)
			(size 0.7112 4.191)
			(layers "B.Cu" "B.Mask" "B.Paste")
			(net "NetC49_1")
		)
		(pad "A23" smd rect
			(at 7.50011 2.7239)
			(size 0.7112 4.191)
			(layers "B.Cu" "B.Mask" "B.Paste")
			(net "GND")
		)
		(pad "A24" smd rect
			(at 8.50011 2.7239)
			(size 0.7112 4.191)
			(layers "B.Cu" "B.Mask" "B.Paste")
			(net "GND")
		)
		(pad "A25" smd rect
			(at 9.5001 2.7239)
			(size 0.7112 4.191)
			(layers "B.Cu" "B.Mask" "B.Paste")
			(net "NetC50_1")
		)
		(pad "A26" smd rect
			(at 10.5001 2.7239)
			(size 0.7112 4.191)
			(layers "B.Cu" "B.Mask" "B.Paste")
			(net "NetC51_1")
		)
		(pad "A27" smd rect
			(at 11.5001 2.7239)
			(size 0.7112 4.191)
			(layers "B.Cu" "B.Mask" "B.Paste")
			(net "GND")
		)
		(pad "A28" smd rect
			(at 12.5001 2.7239)
			(size 0.7112 4.191)
			(layers "B.Cu" "B.Mask" "B.Paste")
			(net "GND")
		)
		(pad "A29" smd rect
			(at 13.5001 2.7239)
			(size 0.7112 4.191)
			(layers "B.Cu" "B.Mask" "B.Paste")
			(net "NetC52_1")
		)
		(pad "A30" smd rect
			(at 14.50009 2.7239)
			(size 0.7112 4.191)
			(layers "B.Cu" "B.Mask" "B.Paste")
			(net "NetC53_1")
		)
		(pad "A31" smd rect
			(at 15.50009 2.7239)
			(size 0.7112 4.191)
			(layers "B.Cu" "B.Mask" "B.Paste")
			(net "GND")
		)
		(pad "A32" smd rect
			(at 16.50009 2.7239)
			(size 0.7112 4.191)
			(layers "B.Cu" "B.Mask" "B.Paste")
		)
		(pad "B1" smd rect
			(at -16.49984 2.7239)
			(size 0.7112 4.191)
			(layers "F.Cu" "F.Mask" "F.Paste")
			(net "+12V_PCIE")
		)
		(pad "B2" smd rect
			(at -15.49985 2.7239)
			(size 0.7112 4.191)
			(layers "F.Cu" "F.Mask" "F.Paste")
			(net "+12V_PCIE")
		)
		(pad "B3" smd rect
			(at -14.49985 2.7239)
			(size 0.7112 4.191)
			(layers "F.Cu" "F.Mask" "F.Paste")
			(net "+12V_PCIE")
		)
		(pad "B4" smd rect
			(at -13.49985 2.7239)
			(size 0.7112 4.191)
			(layers "F.Cu" "F.Mask" "F.Paste")
			(net "GND")
		)
		(pad "B5" smd rect
			(at -12.49985 2.7239)
			(size 0.7112 4.191)
			(layers "F.Cu" "F.Mask" "F.Paste")
		)
		(pad "B6" smd rect
			(at -11.49985 2.7239)
			(size 0.7112 4.191)
			(layers "F.Cu" "F.Mask" "F.Paste")
		)
		(pad "B7" smd rect
			(at -10.49986 2.7239)
			(size 0.7112 4.191)
			(layers "F.Cu" "F.Mask" "F.Paste")
			(net "GND")
		)
		(pad "B8" smd rect
			(at -9.49986 2.7239)
			(size 0.7112 4.191)
			(layers "F.Cu" "F.Mask" "F.Paste")
			(net "+3.3V_PCIE")
		)
		(pad "B9" smd rect
			(at -8.49986 2.7239)
			(size 0.7112 4.191)
			(layers "F.Cu" "F.Mask" "F.Paste")
		)
		(pad "B10" smd rect
			(at -7.49986 2.7239)
			(size 0.7112 4.191)
			(layers "F.Cu" "F.Mask" "F.Paste")
		)
		(pad "B11" smd rect
			(at -6.49986 2.7239)
			(size 0.7112 4.191)
			(layers "F.Cu" "F.Mask" "F.Paste")
		)
		(pad "B12" smd rect
			(at -3.49987 2.7239)
			(size 0.7112 4.191)
			(layers "F.Cu" "F.Mask" "F.Paste")
		)
		(pad "B13" smd rect
			(at -2.49987 2.7239)
			(size 0.7112 4.191)
			(layers "F.Cu" "F.Mask" "F.Paste")
			(net "GND")
		)
		(pad "B14" smd rect
			(at -1.49987 2.7239)
			(size 0.7112 4.191)
			(layers "F.Cu" "F.Mask" "F.Paste")
			(net "PCIE_RX0_P")
		)
		(pad "B15" smd rect
			(at -0.49988 2.7239)
			(size 0.7112 4.191)
			(layers "F.Cu" "F.Mask" "F.Paste")
			(net "PCIE_RX0_N")
		)
		(pad "B16" smd rect
			(at 0.50012 2.7239)
			(size 0.7112 4.191)
			(layers "F.Cu" "F.Mask" "F.Paste")
			(net "GND")
		)
		(pad "B17" smd rect
			(at 1.50012 2.7239)
			(size 0.7112 4.191)
			(layers "F.Cu" "F.Mask" "F.Paste")
			(net "NetP2_B17")
		)
		(pad "B18" smd rect
			(at 2.50012 2.7239)
			(size 0.7112 4.191)
			(layers "F.Cu" "F.Mask" "F.Paste")
			(net "GND")
		)
		(pad "B19" smd rect
			(at 3.50012 2.7239)
			(size 0.7112 4.191)
			(layers "F.Cu" "F.Mask" "F.Paste")
			(net "PCIE_RX1_P")
		)
		(pad "B20" smd rect
			(at 4.50011 2.7239)
			(size 0.7112 4.191)
			(layers "F.Cu" "F.Mask" "F.Paste")
			(net "PCIE_RX1_N")
		)
		(pad "B21" smd rect
			(at 5.50011 2.7239)
			(size 0.7112 4.191)
			(layers "F.Cu" "F.Mask" "F.Paste")
			(net "GND")
		)
		(pad "B22" smd rect
			(at 6.50011 2.7239)
			(size 0.7112 4.191)
			(layers "F.Cu" "F.Mask" "F.Paste")
			(net "GND")
		)
		(pad "B23" smd rect
			(at 7.50011 2.7239)
			(size 0.7112 4.191)
			(layers "F.Cu" "F.Mask" "F.Paste")
			(net "PCIE_RX2_P")
		)
		(pad "B24" smd rect
			(at 8.50011 2.7239)
			(size 0.7112 4.191)
			(layers "F.Cu" "F.Mask" "F.Paste")
			(net "PCIE_RX2_N")
		)
		(pad "B25" smd rect
			(at 9.5001 2.7239)
			(size 0.7112 4.191)
			(layers "F.Cu" "F.Mask" "F.Paste")
			(net "GND")
		)
		(pad "B26" smd rect
			(at 10.5001 2.7239)
			(size 0.7112 4.191)
			(layers "F.Cu" "F.Mask" "F.Paste")
			(net "GND")
		)
		(pad "B27" smd rect
			(at 11.5001 2.7239)
			(size 0.7112 4.191)
			(layers "F.Cu" "F.Mask" "F.Paste")
			(net "PCIE_RX3_P")
		)
		(pad "B28" smd rect
			(at 12.5001 2.7239)
			(size 0.7112 4.191)
			(layers "F.Cu" "F.Mask" "F.Paste")
			(net "PCIE_RX3_N")
		)
		(pad "B29" smd rect
			(at 13.5001 2.7239)
			(size 0.7112 4.191)
			(layers "F.Cu" "F.Mask" "F.Paste")
			(net "GND")
		)
		(pad "B30" smd rect
			(at 14.50009 2.7239)
			(size 0.7112 4.191)
			(layers "F.Cu" "F.Mask" "F.Paste")
		)
		(pad "B31" smd rect
			(at 15.50009 2.2286)
			(size 0.7112 3.2004)
			(layers "F.Cu" "F.Mask" "F.Paste")
			(net "NetP2_B31")
		)
		(pad "B32" smd rect
			(at 16.50009 2.7239)
			(size 0.7112 4.191)
			(layers "F.Cu" "F.Mask" "F.Paste")
			(net "GND")
		)
	)
	(footprint "Vault:FP-BME280-MFG"
		(layer "F.Cu")
		(at 148.238595 88.8286)
		(property "Reference" "U14"
			(at -0.5214 2.776931 0)
			(unlocked yes)
			(layer "F.SilkS")
			(effects
				(font
					(size 0.762 0.762)
					(thickness 0.2286)
				)
			)
		)
		(property "Value" "BME280"
			(at 2.932305 3.470402 0)
			(unlocked yes)
			(layer "F.SilkS")
			(hide yes)
			(effects
				(font
					(size 1.524 1.524)
					(thickness 0.254)
				)
			)
		)
		(sheetname "GPS_IMU_SENSORS")
		(sheetfile "GPS_IMU_SENSORS.kicad_sch")
		(duplicate_pad_numbers_are_jumpers no)
		(fp_line
			(start -1.3 -1.55)
			(end 1.3 -1.55)
			(stroke
				(width 0.2)
				(type solid)
			)
			(layer "F.SilkS")
		)
		(fp_line
			(start -1.3 1.55)
			(end 1.3 1.55)
			(stroke
				(width 0.2)
				(type solid)
			)
			(layer "F.SilkS")
		)
		(fp_circle
			(center 1.85 -0.975)
			(end 1.85 -1.1)
			(stroke
				(width 0.25)
				(type solid)
			)
			(fill no)
			(layer "F.SilkS")
		)
		(fp_line
			(start -1.8 -1.8)
			(end 1.8 -1.8)
			(stroke
				(width 0.2)
				(type solid)
			)
			(layer "F.CrtYd")
		)
		(fp_line
			(start -1.8 1.8)
			(end -1.8 -1.8)
			(stroke
				(width 0.2)
				(type solid)
			)
			(layer "F.CrtYd")
		)
		(fp_line
			(start -1.8 1.8)
			(end 1.8 1.8)
			(stroke
				(width 0.2)
				(type solid)
			)
			(layer "F.CrtYd")
		)
		(fp_line
			(start 1.8 1.8)
			(end 1.8 -1.8)
			(stroke
				(width 0.2)
				(type solid)
			)
			(layer "F.CrtYd")
		)
		(fp_line
			(start -1.8 -1.8)
			(end 1.8 -1.8)
			(stroke
				(width 0.2)
				(type solid)
			)
			(layer "F.Fab")
		)
		(fp_line
			(start -1.8 1.8)
			(end -1.8 -1.8)
			(stroke
				(width 0.2)
				(type solid)
			)
			(layer "F.Fab")
		)
		(fp_line
			(start -1.8 1.8)
			(end 1.8 1.8)
			(stroke
				(width 0.2)
				(type solid)
			)
			(layer "F.Fab")
		)
		(fp_line
			(start -0.5 0)
			(end 0.5 0)
			(stroke
				(width 0.1)
				(type solid)
			)
			(layer "F.Fab")
		)
		(fp_line
			(start 0 0.5)
			(end 0 -0.5)
			(stroke
				(width 0.1)
				(type solid)
			)
			(layer "F.Fab")
		)
		(fp_line
			(start 1.8 1.8)
			(end 1.8 -1.8)
			(stroke
				(width 0.2)
				(type solid)
			)
			(layer "F.Fab")
		)
		(fp_text user "${REFERENCE}"
			(at 0 0.28494 0)
			(unlocked yes)
			(layer "F.Fab")
			(effects
				(font
					(face "Arial")
					(size 0.63 0.63)
					(thickness 0.1)
				)
				(justify left bottom)
			)
		)
		(pad "1" smd rect
			(at 1.025 -0.975)
			(size 0.5 0.35)
			(layers "F.Cu" "F.Mask" "F.Paste")
			(net "GND")
			(solder_mask_margin 0)
			(solder_paste_margin 0)
		)
		(pad "2" smd rect
			(at 1.025 -0.325)
			(size 0.5 0.35)
			(layers "F.Cu" "F.Mask" "F.Paste")
			(net "+3.3V")
			(solder_mask_margin 0)
			(solder_paste_margin 0)
		)
		(pad "3" smd rect
			(at 1.025 0.325)
			(size 0.5 0.35)
			(layers "F.Cu" "F.Mask" "F.Paste")
			(net "SDA")
			(solder_mask_margin 0)
			(solder_paste_margin 0)
		)
		(pad "4" smd rect
			(at 1.025 0.975)
			(size 0.5 0.35)
			(layers "F.Cu" "F.Mask" "F.Paste")
			(net "SCL")
			(solder_mask_margin 0)
			(solder_paste_margin 0)
		)
		(pad "5" smd rect
			(at -1.025 0.975)
			(size 0.5 0.35)
			(layers "F.Cu" "F.Mask" "F.Paste")
			(net "GND")
			(solder_mask_margin 0)
			(solder_paste_margin 0)
		)
		(pad "6" smd rect
			(at -1.025 0.325)
			(size 0.5 0.35)
			(layers "F.Cu" "F.Mask" "F.Paste")
			(net "+3.3V")
			(solder_mask_margin 0)
			(solder_paste_margin 0)
		)
		(pad "7" smd rect
			(at -1.025 -0.325)
			(size 0.5 0.35)
			(layers "F.Cu" "F.Mask" "F.Paste")
			(net "GND")
			(solder_mask_margin 0)
			(solder_paste_margin 0)
		)
		(pad "8" smd rect
			(at -1.025 -0.975)
			(size 0.5 0.35)
			(layers "F.Cu" "F.Mask" "F.Paste")
			(net "+3.3V")
			(solder_mask_margin 0)
			(solder_paste_margin 0)
		)
	)
	(footprint "Resistors:RESC1005X04N"
		(layer "F.Cu")
		(at 136.088595 145.5786 -90)
		(property "Reference" "R24"
			(at 1.35111 0.884735 90)
			(unlocked yes)
			(layer "F.SilkS")
			(effects
				(font
					(size 0.762 0.762)
					(thickness 0.2286)
				)
				(justify left bottom)
			)
		)
		(property "Value" "ERJ-2GE0R00X"
			(at 3.42519 0.2413 0)
			(unlocked yes)
			(layer "F.SilkS")
			(hide yes)
			(effects
				(font
					(size 1.524 1.524)
					(thickness 0.254)
				)
				(justify left bottom)
			)
		)
		(sheetname "PCIe_JTAG")
		(sheetfile "PCIe_JTAG.kicad_sch")
		(duplicate_pad_numbers_are_jumpers no)
		(pad "1" smd rect
			(at -0.425 0)
			(size 0.6 0.65)
			(layers "F.Cu" "F.Mask" "F.Paste")
			(net "PRSNT")
		)
		(pad "2" smd rect
			(at 0.425 0)
			(size 0.6 0.65)
			(layers "F.Cu" "F.Mask" "F.Paste")
			(net "NetP2_B31")
		)
	)
	(footprint "Capacitors:CAPC2012X14N"
		(layer "F.Cu")
		(at 217.888595 87.9786 90)
		(property "Reference" "C7"
			(at 3 0.393345 90)
			(unlocked yes)
			(layer "F.SilkS")
			(effects
				(font
					(size 0.762 0.762)
					(thickness 0.2286)
				)
				(justify left bottom)
			)
		)
		(property "Value" "CAP_0805_10UF_25V"
			(at -15.71879 10.0965 0)
			(unlocked yes)
			(layer "F.SilkS")
			(hide yes)
			(effects
				(font
					(size 1.524 1.524)
					(thickness 0.254)
				)
				(justify left bottom)
			)
		)
		(sheetname "POWER")
		(sheetfile "POWER.kicad_sch")
		(duplicate_pad_numbers_are_jumpers no)
		(fp_line
			(start -0.762 -0.9652)
			(end 0.762 -0.9652)
			(stroke
				(width 0.1524)
				(type solid)
			)
			(layer "F.SilkS")
		)
		(fp_line
			(start -0.762 0.9652)
			(end 0.762 0.9652)
			(stroke
				(width 0.1524)
				(type solid)
			)
			(layer "F.SilkS")
		)
		(pad "1" smd rect
			(at -0.9 0 180)
			(size 1.45 1.15)
			(layers "F.Cu" "F.Mask" "F.Paste")
			(net "+3.3V")
		)
		(pad "2" smd rect
			(at 0.9 0 180)
			(size 1.45 1.15)
			(layers "F.Cu" "F.Mask" "F.Paste")
			(net "GND")
		)
	)
	(footprint "Miscellaneous Connectors:HDR1X4"
		(layer "F.Cu")
		(at 188.948595 52.3286)
		(property "Reference" "P3"
			(at 9.763069 0.228605 270)
			(unlocked yes)
			(layer "F.SilkS")
			(effects
				(font
					(size 0.762 0.762)
					(thickness 0.2286)
				)
			)
		)
		(property "Value" "AUX Sensor"
			(at -2.937002 6.38576 270)
			(unlocked yes)
			(layer "F.SilkS")
			(hide yes)
			(effects
				(font
					(size 1.524 1.524)
					(thickness 0.254)
				)
			)
		)
		(sheetname "GPS_IMU_SENSORS")
		(sheetfile "GPS_IMU_SENSORS.kicad_sch")
		(duplicate_pad_numbers_are_jumpers no)
		(fp_line
			(start -1.27 -1.27)
			(end 8.89 -1.27)
			(stroke
				(width 0.2)
				(type solid)
			)
			(layer "F.SilkS")
		)
		(fp_line
			(start -1.27 1.27)
			(end -1.27 -1.27)
			(stroke
				(width 0.2)
				(type solid)
			)
			(layer "F.SilkS")
		)
		(fp_line
			(start -1.27 1.27)
			(end 8.89 1.27)
			(stroke
				(width 0.2)
				(type solid)
			)
			(layer "F.SilkS")
		)
		(fp_line
			(start 8.89 1.27)
			(end 8.89 -1.27)
			(stroke
				(width 0.2)
				(type solid)
			)
			(layer "F.SilkS")
		)
		(pad "1" thru_hole rect
			(at 0 0)
			(size 1.5 1.5)
			(drill 0.9)
			(layers "*.Cu" "*.Mask")
			(remove_unused_layers no)
			(net "GND")
		)
		(pad "2" thru_hole circle
			(at 2.54 0)
			(size 1.5 1.5)
			(drill 0.9)
			(layers "*.Cu" "*.Mask")
			(remove_unused_layers no)
			(net "+3.3V")
			(thermal_bridge_angle 90)
		)
		(pad "3" thru_hole circle
			(at 5.08 0)
			(size 1.5 1.5)
			(drill 0.9)
			(layers "*.Cu" "*.Mask")
			(remove_unused_layers no)
			(net "SCL")
			(thermal_bridge_angle 90)
		)
		(pad "4" thru_hole circle
			(at 7.62 0)
			(size 1.5 1.5)
			(drill 0.9)
			(layers "*.Cu" "*.Mask")
			(remove_unused_layers no)
			(net "SDA")
			(thermal_bridge_angle 90)
		)
	)
	(footprint "Vault:RESC1608X55X25NL10T15"
		(layer "F.Cu")
		(at 83.238595 96.8286 -90)
		(property "Reference" "R14"
			(at -2.9786 -0.026931 90)
			(unlocked yes)
			(layer "F.SilkS")
			(effects
				(font
					(size 0.762 0.762)
					(thickness 0.2286)
				)
			)
		)
		(property "Value" "49.9R"
			(at 2.835402 -4.73554 0)
			(unlocked yes)
			(layer "F.SilkS")
			(hide yes)
			(effects
				(font
					(size 1.524 1.524)
					(thickness 0.254)
				)
			)
		)
		(sheetname "USER_IO")
		(sheetfile "USER_IO.kicad_sch")
		(duplicate_pad_numbers_are_jumpers no)
		(pad "1" smd rect
			(at -0.7 0)
			(size 0.9 0.7)
			(layers "F.Cu" "F.Mask" "F.Paste")
			(net "NetR14_1")
		)
		(pad "2" smd rect
			(at 0.7 0)
			(size 0.9 0.7)
			(layers "F.Cu" "F.Mask" "F.Paste")
			(net "NetAN1_1")
		)
	)
)
